(kicad_pcb
	(version 20260206)
	(generator "pcbnew")
	(generator_version "10.0")
	(general
		(thickness 1.6)
		(legacy_teardrops no)
	)
	(paper "A4")
	(title_block
		(title "04192023_DAF0TMB3IC0_F0TG_MB_C_brd_V02_OCP.brd")
		(comment 1 "Grand Teton / footprints 6504-6510 of 8354")
	)
	(layers
		(0 "F.Cu" signal "TOP")
		(4 "In1.Cu" signal "GND")
		(6 "In2.Cu" signal "IN1")
		(8 "In3.Cu" signal "GND1")
		(10 "In4.Cu" signal "IN2")
		(12 "In5.Cu" signal "GND2")
		(14 "In6.Cu" signal "IN3")
		(16 "In7.Cu" signal "GND3")
		(18 "In8.Cu" signal "VCC")
		(20 "In9.Cu" signal "VCC1")
		(22 "In10.Cu" signal "GND4")
		(24 "In11.Cu" signal "IN4")
		(26 "In12.Cu" signal "GND5")
		(28 "In13.Cu" signal "IN5")
		(30 "In14.Cu" signal "GND6")
		(32 "In15.Cu" signal "IN6")
		(34 "In16.Cu" signal "GND7")
		(2 "B.Cu" signal "BOTTOM")
		(9 "F.Adhes" user "F.Adhesive")
		(11 "B.Adhes" user "B.Adhesive")
		(13 "F.Paste" user "Package Geometry/Pastemask Top")
		(15 "B.Paste" user "Package Geometry/Pastemask Bottom")
		(5 "F.SilkS" user "Ref Des/Silkscreen Top")
		(7 "B.SilkS" user "Ref Des/Silkscreen Bottom")
		(1 "F.Mask" user "Board Geometry/Soldermask Top")
		(3 "B.Mask" user "Board Geometry/Soldermask Bottom")
		(17 "Dwgs.User" user "User.Drawings")
		(19 "Cmts.User" user "User.Comments")
		(21 "Eco1.User" user "User.Eco1")
		(23 "Eco2.User" user "User.Eco2")
		(25 "Edge.Cuts" user "Board Geometry/Outline")
		(27 "Margin" user)
		(31 "F.CrtYd" user "Package Geometry/Place Bound Top")
		(29 "B.CrtYd" user "Package Geometry/Place Bound Bottom")
		(35 "F.Fab" user "Ref Des/Assembly Top")
		(33 "B.Fab" user "Ref Des/Assembly Bottom")
	)
	(footprint ""
		(layer "B.Cu")
		(at 241.938048 -289.533838 -90)
		(property "Reference" "PR6501"
			(at 0 0 90)
			(layer "B.SilkS")
			(hide yes)
			(effects
				(font
					(size 1.27 1.27)
				)
				(justify mirror)
			)
		)
		(property "Value" ""
			(at 0 0 90)
			(layer "B.Fab")
			(effects
				(font
					(size 1.27 1.27)
				)
				(justify mirror)
			)
		)
		(duplicate_pad_numbers_are_jumpers no)
		(fp_line
			(start -0.7874 0.4064)
			(end 0.7874 0.4064)
			(stroke
				(width 0.1524)
				(type default)
			)
			(layer "B.SilkS")
		)
		(fp_line
			(start 0.7874 0.4064)
			(end 0.7874 -0.4064)
			(stroke
				(width 0.1524)
				(type default)
			)
			(layer "B.SilkS")
		)
		(fp_line
			(start -0.7874 -0.4064)
			(end -0.7874 0.4064)
			(stroke
				(width 0.1524)
				(type default)
			)
			(layer "B.SilkS")
		)
		(fp_line
			(start 0.7874 -0.4064)
			(end -0.7874 -0.4064)
			(stroke
				(width 0.1524)
				(type default)
			)
			(layer "B.SilkS")
		)
		(fp_line
			(start -0.67945 0.3048)
			(end -0.120396 0.3048)
			(stroke
				(width 0.1)
				(type default)
			)
			(layer "B.Fab")
		)
		(fp_line
			(start -0.120396 0.3048)
			(end -0.120396 0.2794)
			(stroke
				(width 0.1)
				(type default)
			)
			(layer "B.Fab")
		)
		(fp_line
			(start 0.12065 0.3048)
			(end 0.67945 0.3048)
			(stroke
				(width 0.1)
				(type default)
			)
			(layer "B.Fab")
		)
		(fp_line
			(start 0.67945 0.3048)
			(end 0.67945 -0.305054)
			(stroke
				(width 0.1)
				(type default)
			)
			(layer "B.Fab")
		)
		(fp_line
			(start -0.120396 0.2794)
			(end 0.12065 0.2794)
			(stroke
				(width 0.1)
				(type default)
			)
			(layer "B.Fab")
		)
		(fp_line
			(start 0.12065 0.2794)
			(end 0.12065 0.3048)
			(stroke
				(width 0.1)
				(type default)
			)
			(layer "B.Fab")
		)
		(fp_line
			(start -0.12065 -0.2794)
			(end -0.12065 -0.3048)
			(stroke
				(width 0.1)
				(type default)
			)
			(layer "B.Fab")
		)
		(fp_line
			(start 0.12065 -0.2794)
			(end -0.12065 -0.2794)
			(stroke
				(width 0.1)
				(type default)
			)
			(layer "B.Fab")
		)
		(fp_line
			(start -0.67945 -0.3048)
			(end -0.67945 0.3048)
			(stroke
				(width 0.1)
				(type default)
			)
			(layer "B.Fab")
		)
		(fp_line
			(start -0.12065 -0.3048)
			(end -0.67945 -0.3048)
			(stroke
				(width 0.1)
				(type default)
			)
			(layer "B.Fab")
		)
		(fp_line
			(start 0.12065 -0.305054)
			(end 0.12065 -0.2794)
			(stroke
				(width 0.1)
				(type default)
			)
			(layer "B.Fab")
		)
		(fp_line
			(start 0.67945 -0.305054)
			(end 0.12065 -0.305054)
			(stroke
				(width 0.1)
				(type default)
			)
			(layer "B.Fab")
		)
		(pad "1" smd circle
			(at 0.40005 0 90)
			(size 0 0)
			(layers "B.Cu" "B.Mask" "B.Paste")
			(net "P3V3_AUX")
		)
		(pad "2" smd circle
			(at -0.40005 0 90)
			(size 0 0)
			(layers "B.Cu" "B.Mask" "B.Paste")
			(net "P1V8_RETIMER_CPU0_VCC")
		)
	)
	(footprint ""
		(layer "B.Cu")
		(at 74.478134 -326.232012 -90)
		(property "Reference" "PC395_1"
			(at 0 0 90)
			(layer "B.SilkS")
			(hide yes)
			(effects
				(font
					(size 1.27 1.27)
				)
				(justify mirror)
			)
		)
		(property "Value" ""
			(at 0 0 90)
			(layer "B.Fab")
			(effects
				(font
					(size 1.27 1.27)
				)
				(justify mirror)
			)
		)
		(duplicate_pad_numbers_are_jumpers no)
		(fp_line
			(start -1.524 0.762)
			(end 1.524 0.762)
			(stroke
				(width 0.1524)
				(type default)
			)
			(layer "B.SilkS")
		)
		(fp_line
			(start 1.524 0.762)
			(end 1.524 -0.762)
			(stroke
				(width 0.1524)
				(type default)
			)
			(layer "B.SilkS")
		)
		(fp_line
			(start -1.524 -0.762)
			(end -1.524 0.762)
			(stroke
				(width 0.1524)
				(type default)
			)
			(layer "B.SilkS")
		)
		(fp_line
			(start 1.524 -0.762)
			(end -1.524 -0.762)
			(stroke
				(width 0.1524)
				(type default)
			)
			(layer "B.SilkS")
		)
		(fp_line
			(start -1.1049 0.724916)
			(end -1.1049 -0.724916)
			(stroke
				(width 0.1)
				(type default)
			)
			(layer "B.Fab")
		)
		(fp_line
			(start 1.1049 0.724916)
			(end -1.1049 0.724916)
			(stroke
				(width 0.1)
				(type default)
			)
			(layer "B.Fab")
		)
		(fp_line
			(start -1.1049 -0.724916)
			(end 1.1049 -0.724916)
			(stroke
				(width 0.1)
				(type default)
			)
			(layer "B.Fab")
		)
		(fp_line
			(start 1.1049 -0.724916)
			(end 1.1049 0.724916)
			(stroke
				(width 0.1)
				(type default)
			)
			(layer "B.Fab")
		)
		(pad "1" smd rect
			(at 0.889 0 270)
			(size 1.016 1.27)
			(layers "B.Cu" "B.Mask" "B.Paste")
			(net "PVDDCR_CPU1_P1")
		)
		(pad "2" smd rect
			(at -0.889 0 270)
			(size 1.016 1.27)
			(layers "B.Cu" "B.Mask" "B.Paste")
			(net "GND")
		)
	)
	(footprint ""
		(layer "B.Cu")
		(at 392.961622 -400.19605 180)
		(property "Reference" "C1025"
			(at 0 0 0)
			(layer "B.SilkS")
			(hide yes)
			(effects
				(font
					(size 1.27 1.27)
				)
				(justify mirror)
			)
		)
		(property "Value" ""
			(at 0 0 0)
			(layer "B.Fab")
			(effects
				(font
					(size 1.27 1.27)
				)
				(justify mirror)
			)
		)
		(duplicate_pad_numbers_are_jumpers no)
		(fp_line
			(start 1.524 0.762)
			(end 1.524 -0.762)
			(stroke
				(width 0.1524)
				(type default)
			)
			(layer "B.SilkS")
		)
		(fp_line
			(start 1.524 -0.762)
			(end -1.524 -0.762)
			(stroke
				(width 0.1524)
				(type default)
			)
			(layer "B.SilkS")
		)
		(fp_line
			(start -1.524 0.762)
			(end 1.524 0.762)
			(stroke
				(width 0.1524)
				(type default)
			)
			(layer "B.SilkS")
		)
		(fp_line
			(start -1.524 -0.762)
			(end -1.524 0.762)
			(stroke
				(width 0.1524)
				(type default)
			)
			(layer "B.SilkS")
		)
		(fp_line
			(start 1.1049 0.724916)
			(end -1.1049 0.724916)
			(stroke
				(width 0.1)
				(type default)
			)
			(layer "B.Fab")
		)
		(fp_line
			(start 1.1049 -0.724916)
			(end 1.1049 0.724916)
			(stroke
				(width 0.1)
				(type default)
			)
			(layer "B.Fab")
		)
		(fp_line
			(start -1.1049 0.724916)
			(end -1.1049 -0.724916)
			(stroke
				(width 0.1)
				(type default)
			)
			(layer "B.Fab")
		)
		(fp_line
			(start -1.1049 -0.724916)
			(end 1.1049 -0.724916)
			(stroke
				(width 0.1)
				(type default)
			)
			(layer "B.Fab")
		)
		(pad "1" smd rect
			(at 0.889 0 180)
			(size 1.016 1.27)
			(layers "B.Cu" "B.Mask" "B.Paste")
			(net "P0V9_CPU0_RT3_2A")
		)
		(pad "2" smd rect
			(at -0.889 0 180)
			(size 1.016 1.27)
			(layers "B.Cu" "B.Mask" "B.Paste")
			(net "GND")
		)
	)
	(footprint ""
		(layer "B.Cu")
		(at 206.429356 -382.596136 180)
		(property "Reference" "PR2523"
			(at 0 0 0)
			(layer "B.SilkS")
			(hide yes)
			(effects
				(font
					(size 1.27 1.27)
				)
				(justify mirror)
			)
		)
		(property "Value" ""
			(at 0 0 0)
			(layer "B.Fab")
			(effects
				(font
					(size 1.27 1.27)
				)
				(justify mirror)
			)
		)
		(duplicate_pad_numbers_are_jumpers no)
		(fp_line
			(start 0.7874 0.4064)
			(end 0.7874 -0.4064)
			(stroke
				(width 0.1524)
				(type default)
			)
			(layer "B.SilkS")
		)
		(fp_line
			(start 0.7874 -0.4064)
			(end -0.7874 -0.4064)
			(stroke
				(width 0.1524)
				(type default)
			)
			(layer "B.SilkS")
		)
		(fp_line
			(start -0.7874 0.4064)
			(end 0.7874 0.4064)
			(stroke
				(width 0.1524)
				(type default)
			)
			(layer "B.SilkS")
		)
		(fp_line
			(start -0.7874 -0.4064)
			(end -0.7874 0.4064)
			(stroke
				(width 0.1524)
				(type default)
			)
			(layer "B.SilkS")
		)
		(fp_line
			(start 0.67945 0.3048)
			(end 0.67945 -0.305054)
			(stroke
				(width 0.1)
				(type default)
			)
			(layer "B.Fab")
		)
		(fp_line
			(start 0.67945 -0.305054)
			(end 0.12065 -0.305054)
			(stroke
				(width 0.1)
				(type default)
			)
			(layer "B.Fab")
		)
		(fp_line
			(start 0.12065 0.3048)
			(end 0.67945 0.3048)
			(stroke
				(width 0.1)
				(type default)
			)
			(layer "B.Fab")
		)
		(fp_line
			(start 0.12065 0.2794)
			(end 0.12065 0.3048)
			(stroke
				(width 0.1)
				(type default)
			)
			(layer "B.Fab")
		)
		(fp_line
			(start 0.12065 -0.2794)
			(end -0.12065 -0.2794)
			(stroke
				(width 0.1)
				(type default)
			)
			(layer "B.Fab")
		)
		(fp_line
			(start 0.12065 -0.305054)
			(end 0.12065 -0.2794)
			(stroke
				(width 0.1)
				(type default)
			)
			(layer "B.Fab")
		)
		(fp_line
			(start -0.120396 0.3048)
			(end -0.120396 0.2794)
			(stroke
				(width 0.1)
				(type default)
			)
			(layer "B.Fab")
		)
		(fp_line
			(start -0.120396 0.2794)
			(end 0.12065 0.2794)
			(stroke
				(width 0.1)
				(type default)
			)
			(layer "B.Fab")
		)
		(fp_line
			(start -0.12065 -0.2794)
			(end -0.12065 -0.3048)
			(stroke
				(width 0.1)
				(type default)
			)
			(layer "B.Fab")
		)
		(fp_line
			(start -0.12065 -0.3048)
			(end -0.67945 -0.3048)
			(stroke
				(width 0.1)
				(type default)
			)
			(layer "B.Fab")
		)
		(fp_line
			(start -0.67945 0.3048)
			(end -0.120396 0.3048)
			(stroke
				(width 0.1)
				(type default)
			)
			(layer "B.Fab")
		)
		(fp_line
			(start -0.67945 -0.3048)
			(end -0.67945 0.3048)
			(stroke
				(width 0.1)
				(type default)
			)
			(layer "B.Fab")
		)
		(pad "1" smd circle
			(at 0.40005 0)
			(size 0 0)
			(layers "B.Cu" "B.Mask" "B.Paste")
			(net "P12V_HSC_SENSE2_P")
		)
		(pad "2" smd circle
			(at -0.40005 0)
			(size 0 0)
			(layers "B.Cu" "B.Mask" "B.Paste")
			(net "P12V_HSC_SENSE2_R4_P")
		)
	)
	(footprint ""
		(layer "B.Cu")
		(at 373.075454 -264.35431)
		(property "Reference" "C2628"
			(at 0 0 0)
			(layer "B.SilkS")
			(hide yes)
			(effects
				(font
					(size 1.27 1.27)
				)
				(justify mirror)
			)
		)
		(property "Value" ""
			(at 0 0 0)
			(layer "B.Fab")
			(effects
				(font
					(size 1.27 1.27)
				)
				(justify mirror)
			)
		)
		(duplicate_pad_numbers_are_jumpers no)
		(fp_line
			(start -0.7874 -0.4064)
			(end -0.7874 0.4064)
			(stroke
				(width 0.1524)
				(type default)
			)
			(layer "B.SilkS")
		)
		(fp_line
			(start -0.7874 0.4064)
			(end 0.7874 0.4064)
			(stroke
				(width 0.1524)
				(type default)
			)
			(layer "B.SilkS")
		)
		(fp_line
			(start 0.7874 -0.4064)
			(end -0.7874 -0.4064)
			(stroke
				(width 0.1524)
				(type default)
			)
			(layer "B.SilkS")
		)
		(fp_line
			(start 0.7874 0.4064)
			(end 0.7874 -0.4064)
			(stroke
				(width 0.1524)
				(type default)
			)
			(layer "B.SilkS")
		)
		(fp_line
			(start -0.67945 -0.3048)
			(end -0.67945 0.3048)
			(stroke
				(width 0.1)
				(type default)
			)
			(layer "B.Fab")
		)
		(fp_line
			(start -0.67945 0.3048)
			(end -0.120396 0.3048)
			(stroke
				(width 0.1)
				(type default)
			)
			(layer "B.Fab")
		)
		(fp_line
			(start -0.12065 -0.3048)
			(end -0.67945 -0.3048)
			(stroke
				(width 0.1)
				(type default)
			)
			(layer "B.Fab")
		)
		(fp_line
			(start -0.12065 -0.2794)
			(end -0.12065 -0.3048)
			(stroke
				(width 0.1)
				(type default)
			)
			(layer "B.Fab")
		)
		(fp_line
			(start -0.120396 0.2794)
			(end 0.12065 0.2794)
			(stroke
				(width 0.1)
				(type default)
			)
			(layer "B.Fab")
		)
		(fp_line
			(start -0.120396 0.3048)
			(end -0.120396 0.2794)
			(stroke
				(width 0.1)
				(type default)
			)
			(layer "B.Fab")
		)
		(fp_line
			(start 0.12065 -0.305054)
			(end 0.12065 -0.2794)
			(stroke
				(width 0.1)
				(type default)
			)
			(layer "B.Fab")
		)
		(fp_line
			(start 0.12065 -0.2794)
			(end -0.12065 -0.2794)
			(stroke
				(width 0.1)
				(type default)
			)
			(layer "B.Fab")
		)
		(fp_line
			(start 0.12065 0.2794)
			(end 0.12065 0.3048)
			(stroke
				(width 0.1)
				(type default)
			)
			(layer "B.Fab")
		)
		(fp_line
			(start 0.12065 0.3048)
			(end 0.67945 0.3048)
			(stroke
				(width 0.1)
				(type default)
			)
			(layer "B.Fab")
		)
		(fp_line
			(start 0.67945 -0.305054)
			(end 0.12065 -0.305054)
			(stroke
				(width 0.1)
				(type default)
			)
			(layer "B.Fab")
		)
		(fp_line
			(start 0.67945 0.3048)
			(end 0.67945 -0.305054)
			(stroke
				(width 0.1)
				(type default)
			)
			(layer "B.Fab")
		)
		(pad "1" smd circle
			(at 0.40005 0 180)
			(size 0 0)
			(layers "B.Cu" "B.Mask" "B.Paste")
			(net "PVDD11_S3_P0")
		)
		(pad "2" smd circle
			(at -0.40005 0 180)
			(size 0 0)
			(layers "B.Cu" "B.Mask" "B.Paste")
			(net "GND")
		)
	)
	(footprint ""
		(layer "B.Cu")
		(at 159.615632 -193.949066 -90)
		(property "Reference" "R990"
			(at 0 0 90)
			(layer "B.SilkS")
			(hide yes)
			(effects
				(font
					(size 1.27 1.27)
				)
				(justify mirror)
			)
		)
		(property "Value" ""
			(at 0 0 90)
			(layer "B.Fab")
			(effects
				(font
					(size 1.27 1.27)
				)
				(justify mirror)
			)
		)
		(duplicate_pad_numbers_are_jumpers no)
		(fp_line
			(start -0.7874 0.4064)
			(end 0.7874 0.4064)
			(stroke
				(width 0.1524)
				(type default)
			)
			(layer "B.SilkS")
		)
		(fp_line
			(start 0.7874 0.4064)
			(end 0.7874 -0.4064)
			(stroke
				(width 0.1524)
				(type default)
			)
			(layer "B.SilkS")
		)
		(fp_line
			(start -0.7874 -0.4064)
			(end -0.7874 0.4064)
			(stroke
				(width 0.1524)
				(type default)
			)
			(layer "B.SilkS")
		)
		(fp_line
			(start 0.7874 -0.4064)
			(end -0.7874 -0.4064)
			(stroke
				(width 0.1524)
				(type default)
			)
			(layer "B.SilkS")
		)
		(fp_line
			(start -0.67945 0.3048)
			(end -0.120396 0.3048)
			(stroke
				(width 0.1)
				(type default)
			)
			(layer "B.Fab")
		)
		(fp_line
			(start -0.120396 0.3048)
			(end -0.120396 0.2794)
			(stroke
				(width 0.1)
				(type default)
			)
			(layer "B.Fab")
		)
		(fp_line
			(start 0.12065 0.3048)
			(end 0.67945 0.3048)
			(stroke
				(width 0.1)
				(type default)
			)
			(layer "B.Fab")
		)
		(fp_line
			(start 0.67945 0.3048)
			(end 0.67945 -0.305054)
			(stroke
				(width 0.1)
				(type default)
			)
			(layer "B.Fab")
		)
		(fp_line
			(start -0.120396 0.2794)
			(end 0.12065 0.2794)
			(stroke
				(width 0.1)
				(type default)
			)
			(layer "B.Fab")
		)
		(fp_line
			(start 0.12065 0.2794)
			(end 0.12065 0.3048)
			(stroke
				(width 0.1)
				(type default)
			)
			(layer "B.Fab")
		)
		(fp_line
			(start -0.12065 -0.2794)
			(end -0.12065 -0.3048)
			(stroke
				(width 0.1)
				(type default)
			)
			(layer "B.Fab")
		)
		(fp_line
			(start 0.12065 -0.2794)
			(end -0.12065 -0.2794)
			(stroke
				(width 0.1)
				(type default)
			)
			(layer "B.Fab")
		)
		(fp_line
			(start -0.67945 -0.3048)
			(end -0.67945 0.3048)
			(stroke
				(width 0.1)
				(type default)
			)
			(layer "B.Fab")
		)
		(fp_line
			(start -0.12065 -0.3048)
			(end -0.67945 -0.3048)
			(stroke
				(width 0.1)
				(type default)
			)
			(layer "B.Fab")
		)
		(fp_line
			(start 0.12065 -0.305054)
			(end 0.12065 -0.2794)
			(stroke
				(width 0.1)
				(type default)
			)
			(layer "B.Fab")
		)
		(fp_line
			(start 0.67945 -0.305054)
			(end 0.12065 -0.305054)
			(stroke
				(width 0.1)
				(type default)
			)
			(layer "B.Fab")
		)
		(pad "1" smd rect
			(at 0.40005 0 270)
			(size 0.4572 0.508)
			(layers "B.Cu" "B.Mask" "B.Paste")
			(net "I3C_1_SPD_DDRGL_CPU1_R_SCL")
		)
		(pad "2" smd rect
			(at -0.40005 0 270)
			(size 0.4572 0.508)
			(layers "B.Cu" "B.Mask" "B.Paste")
			(net "I3C_SPD_DDRGL_CPU1_BYPASS_SCL")
		)
	)
	(footprint ""
		(layer "B.Cu")
		(at 110.149386 -246.447564 -120)
		(property "Reference" "C2340"
			(at 0 0 60)
			(layer "B.SilkS")
			(hide yes)
			(effects
				(font
					(size 1.27 1.27)
				)
				(justify mirror)
			)
		)
		(property "Value" ""
			(at 0 0 60)
			(layer "B.Fab")
			(effects
				(font
					(size 1.27 1.27)
				)
				(justify mirror)
			)
		)
		(duplicate_pad_numbers_are_jumpers no)
		(fp_line
			(start 0.787516 0.406438)
			(end 0.787425 -0.40652)
			(stroke
				(width 0.1524)
				(type default)
			)
			(layer "B.SilkS")
		)
		(fp_line
			(start 0.787425 -0.40652)
			(end -0.787516 -0.406438)
			(stroke
				(width 0.1524)
				(type default)
			)
			(layer "B.SilkS")
		)
		(fp_line
			(start -0.787425 0.40652)
			(end 0.787516 0.406438)
			(stroke
				(width 0.1524)
				(type default)
			)
			(layer "B.SilkS")
		)
		(fp_line
			(start -0.787516 -0.406438)
			(end -0.787425 0.40652)
			(stroke
				(width 0.1524)
				(type default)
			)
			(layer "B.SilkS")
		)
		(fp_line
			(start 0.679568 0.304811)
			(end 0.679373 -0.305128)
			(stroke
				(width 0.1)
				(type default)
			)
			(layer "B.Fab")
		)
		(fp_line
			(start 0.120605 0.304905)
			(end 0.679568 0.304811)
			(stroke
				(width 0.1)
				(type default)
			)
			(layer "B.Fab")
		)
		(fp_line
			(start 0.120554 0.279418)
			(end 0.120605 0.304905)
			(stroke
				(width 0.1)
				(type default)
			)
			(layer "B.Fab")
		)
		(fp_line
			(start -0.120316 0.304686)
			(end -0.12024 0.279419)
			(stroke
				(width 0.1)
				(type default)
			)
			(layer "B.Fab")
		)
		(fp_line
			(start -0.12024 0.279419)
			(end 0.120554 0.279418)
			(stroke
				(width 0.1)
				(type default)
			)
			(layer "B.Fab")
		)
		(fp_line
			(start 0.679373 -0.305128)
			(end 0.120629 -0.30516)
			(stroke
				(width 0.1)
				(type default)
			)
			(layer "B.Fab")
		)
		(fp_line
			(start -0.6795 0.304908)
			(end -0.120316 0.304686)
			(stroke
				(width 0.1)
				(type default)
			)
			(layer "B.Fab")
		)
		(fp_line
			(start 0.120587 -0.279326)
			(end -0.120554 -0.279418)
			(stroke
				(width 0.1)
				(type default)
			)
			(layer "B.Fab")
		)
		(fp_line
			(start 0.120629 -0.30516)
			(end 0.120587 -0.279326)
			(stroke
				(width 0.1)
				(type default)
			)
			(layer "B.Fab")
		)
		(fp_line
			(start -0.120554 -0.279418)
			(end -0.120605 -0.304905)
			(stroke
				(width 0.1)
				(type default)
			)
			(layer "B.Fab")
		)
		(fp_line
			(start -0.120605 -0.304905)
			(end -0.679568 -0.304811)
			(stroke
				(width 0.1)
				(type default)
			)
			(layer "B.Fab")
		)
		(fp_line
			(start -0.679568 -0.304811)
			(end -0.6795 0.304908)
			(stroke
				(width 0.1)
				(type default)
			)
			(layer "B.Fab")
		)
		(pad "1" smd circle
			(at 0.40005 0 60)
			(size 0 0)
			(layers "B.Cu" "B.Mask" "B.Paste")
			(net "PVDDCR_CPU0_P1")
		)
		(pad "2" smd circle
			(at -0.40005 0 60)
			(size 0 0)
			(layers "B.Cu" "B.Mask" "B.Paste")
			(net "GND")
		)
	)
)
